FILE_TYPE = CONNECTIVITY;
{Allegro Design Entry HDL 17.4-2019 S026 (4007227) 1/17/2022}
"PAGE_NUMBER" = 37;
0"NC";
1"M_A_CPU1_SA_DQ<31:0>";
2"M_A_CPU1_SB_DQ<31:0>";
3"M_A_CPU1_SA_CB<7:0>";
4"M_A_CPU1_SB_CB<7:0>";
5"M_A_CPU1_SA_DQS_DP<9:0>";
6"M_A_CPU1_SA_DQS_DN<9:0>";
7"M_A_CPU1_SB_DQS_DN<9:0>";
8"M_A_CPU1_SB_DQS_DP<9:0>";
9"M_A_CPU1_SA_CA<6:0>";
10"M_A_CPU1_SB_CA<6:0>";
11"M_A_CPU1_ALERT_N";
12"M_A_CPU1_ALERT_R_N";
13"TP_M_A_CPU1_SA_TEST40";
14"TP_M_A_CPU1_SA_TEST39A";
15"M_A_CPU1_CLK_DP<0>";
16"M_A_CPU1_CLK_DN<0>";
17"M_A_CPU1_SA_CS_N<0>";
18"M_A_CPU1_SA_CS_N<1>";
19"M_A_CPU1_SA_RSP<0>";
20"M_A_CPU1_SA_PAR";
21"M_A_CPU1_SB_CS_N<0>";
22"M_A_CPU1_SB_CS_N<1>";
23"M_A_CPU1_SB_RSP<0>";
24"M_A_CPU1_SB_PAR";
25"M_A_CPU1_RESET_N";
26"M_A_CPU1_SB_CA<6>";
27"M_A_CPU1_SA_CA<6>";
28"M_A_CPU1_SB_CA<5>";
29"M_A_CPU1_SA_CA<5>";
30"M_A_CPU1_SB_CA<4>";
31"M_A_CPU1_SA_CA<4>";
32"M_A_CPU1_SB_CA<3>";
33"M_A_CPU1_SA_CA<3>";
34"M_A_CPU1_SB_CA<2>";
35"M_A_CPU1_SA_CA<2>";
36"M_A_CPU1_SB_CA<1>";
37"M_A_CPU1_SA_CA<1>";
38"M_A_CPU1_SB_CA<0>";
39"M_A_CPU1_SA_CA<0>";
40"M_A_CPU1_SB_DQS_DN<9>";
41"M_A_CPU1_SB_DQS_DP<9>";
42"M_A_CPU1_SB_DQS_DP<0>";
43"M_A_CPU1_SB_DQS_DN<4>";
44"M_A_CPU1_SB_DQS_DN<3>";
45"M_A_CPU1_SB_DQS_DN<2>";
46"M_A_CPU1_SB_DQS_DN<1>";
47"M_A_CPU1_SB_DQS_DN<0>";
48"M_A_CPU1_SB_DQS_DP<8>";
49"M_A_CPU1_SB_DQS_DP<7>";
50"M_A_CPU1_SB_DQS_DP<6>";
51"M_A_CPU1_SB_DQS_DP<5>";
52"M_A_CPU1_SB_DQS_DP<4>";
53"M_A_CPU1_SB_DQS_DN<8>";
54"M_A_CPU1_SB_DQS_DP<3>";
55"M_A_CPU1_SB_DQS_DN<7>";
56"M_A_CPU1_SB_DQS_DP<2>";
57"M_A_CPU1_SB_DQS_DN<6>";
58"M_A_CPU1_SB_DQS_DP<1>";
59"M_A_CPU1_SB_DQS_DN<5>";
60"M_A_CPU1_SA_DQS_DP<6>";
61"M_A_CPU1_SA_DQS_DP<5>";
62"M_A_CPU1_SA_DQS_DN<9>";
63"M_A_CPU1_SA_DQS_DP<4>";
64"M_A_CPU1_SA_DQS_DN<8>";
65"M_A_CPU1_SA_DQS_DP<3>";
66"M_A_CPU1_SA_DQS_DN<7>";
67"M_A_CPU1_SA_DQS_DP<2>";
68"M_A_CPU1_SA_DQS_DN<6>";
69"M_A_CPU1_SA_DQS_DP<1>";
70"M_A_CPU1_SA_DQS_DN<5>";
71"M_A_CPU1_SA_DQS_DP<0>";
72"M_A_CPU1_SA_DQS_DN<4>";
73"M_A_CPU1_SA_DQS_DN<3>";
74"M_A_CPU1_SA_DQS_DN<2>";
75"M_A_CPU1_SA_DQS_DN<1>";
76"M_A_CPU1_SA_DQS_DN<0>";
77"M_A_CPU1_SA_DQS_DP<9>";
78"M_A_CPU1_SA_DQS_DP<8>";
79"M_A_CPU1_SA_DQS_DP<7>";
80"M_A_CPU1_SB_CB<7>";
81"M_A_CPU1_SB_CB<6>";
82"M_A_CPU1_SB_CB<5>";
83"M_A_CPU1_SB_CB<4>";
84"M_A_CPU1_SB_CB<3>";
85"M_A_CPU1_SB_CB<2>";
86"M_A_CPU1_SB_CB<1>";
87"M_A_CPU1_SB_CB<0>";
88"M_A_CPU1_SB_DQ<28>";
89"M_A_CPU1_SB_DQ<27>";
90"M_A_CPU1_SB_DQ<26>";
91"M_A_CPU1_SB_DQ<25>";
92"M_A_CPU1_SB_DQ<24>";
93"M_A_CPU1_SB_DQ<23>";
94"M_A_CPU1_SA_CB<7>";
95"M_A_CPU1_SA_CB<6>";
96"M_A_CPU1_SB_DQ<31>";
97"M_A_CPU1_SA_CB<5>";
98"M_A_CPU1_SB_DQ<30>";
99"M_A_CPU1_SA_CB<4>";
100"M_A_CPU1_SA_CB<3>";
101"M_A_CPU1_SA_CB<2>";
102"M_A_CPU1_SA_CB<1>";
103"M_A_CPU1_SA_CB<0>";
104"M_A_CPU1_SB_DQ<29>";
105"M_A_CPU1_SB_DQ<17>";
106"M_A_CPU1_SB_DQ<16>";
107"M_A_CPU1_SB_DQ<15>";
108"M_A_CPU1_SB_DQ<14>";
109"M_A_CPU1_SB_DQ<13>";
110"M_A_CPU1_SB_DQ<12>";
111"M_A_CPU1_SB_DQ<11>";
112"M_A_CPU1_SB_DQ<22>";
113"M_A_CPU1_SB_DQ<10>";
114"M_A_CPU1_SB_DQ<21>";
115"M_A_CPU1_SB_DQ<20>";
116"M_A_CPU1_SB_DQ<9>";
117"M_A_CPU1_SB_DQ<8>";
118"M_A_CPU1_SB_DQ<7>";
119"M_A_CPU1_SB_DQ<6>";
120"M_A_CPU1_SB_DQ<5>";
121"M_A_CPU1_SB_DQ<4>";
122"M_A_CPU1_SB_DQ<19>";
123"M_A_CPU1_SB_DQ<18>";
124"M_A_CPU1_SB_DQ<2>";
125"M_A_CPU1_SB_DQ<1>";
126"M_A_CPU1_SB_DQ<0>";
127"M_A_CPU1_SA_DQ<19>";
128"M_A_CPU1_SA_DQ<18>";
129"M_A_CPU1_SA_DQ<29>";
130"M_A_CPU1_SA_DQ<28>";
131"M_A_CPU1_SA_DQ<27>";
132"M_A_CPU1_SA_DQ<26>";
133"M_A_CPU1_SA_DQ<25>";
134"M_A_CPU1_SA_DQ<24>";
135"M_A_CPU1_SA_DQ<23>";
136"M_A_CPU1_SA_DQ<22>";
137"M_A_CPU1_SA_DQ<21>";
138"M_A_CPU1_SA_DQ<20>";
139"M_A_CPU1_SA_DQ<31>";
140"M_A_CPU1_SA_DQ<30>";
141"M_A_CPU1_SB_DQ<3>";
142"M_A_CPU1_SA_DQ<3>";
143"M_A_CPU1_SA_DQ<2>";
144"M_A_CPU1_SA_DQ<1>";
145"M_A_CPU1_SA_DQ<0>";
146"M_A_CPU1_SA_DQ<17>";
147"M_A_CPU1_SA_DQ<16>";
148"M_A_CPU1_SA_DQ<15>";
149"M_A_CPU1_SA_DQ<14>";
150"M_A_CPU1_SA_DQ<13>";
151"M_A_CPU1_SA_DQ<9>";
152"M_A_CPU1_SA_DQ<12>";
153"M_A_CPU1_SA_DQ<8>";
154"M_A_CPU1_SA_DQ<11>";
155"M_A_CPU1_SA_DQ<7>";
156"M_A_CPU1_SA_DQ<10>";
157"M_A_CPU1_SA_DQ<6>";
158"M_A_CPU1_SA_DQ<5>";
159"M_A_CPU1_SA_DQ<4>";
%"GENOA_SP5"
"1","(-4575,3675)","0","pure_quanta","I167";
;
LOCATION"U26"
$SEC"1"
CDS_SEC"1"
PART_TYPE"SMLF"
MATERIAL"IO"
VALUE"SOCKET6096_13568-001"
CDS_LIB"pure_quanta"
NEEDS_NO_SIZE"TRUE"
CDS_LMAN_SYM_OUTLINE"-650,2500,650,-2500"
PART_NUMBER"DGA^6000030";
"TEST40"
$PN"C60"13;
"TEST39A"
$PN"BF72"14;
"MA1_CLK_L"
$PN"BG74"0;
"MA0_CLK_L"
$PN"BD74"16;
"MA1_CLK_H"
$PN"BF74"0;
"MAB_DQS_H9"
$PN"BV74"41;
"MA0_CLK_H"
$PN"BC74"15;
"MAB_PAR"
$PN"BL74"24;
"MAA_PAR"
$PN"BC73"20;
"MAA0_CS_L0"
$PN"AV74"17;
"MAA_DATA3"
$PN"G73"142;
"MAA_DQS_H6"
$PN"R73"60;
"MAB_CA6"
$PN"BK74"26;
"MAB_DATA2"
$PN"CC74"124;
"MAB_DATA17"
$PN"CR73"105;
"MAB_DATA28"
$PN"DD74"88;
"MAB_DQS_H0"
$PN"CD74"42;
"MAB_DQS_L4"
$PN"BW73"43;
"MAA_CA6"
$PN"BB72"27;
"MAA_DATA2"
$PN"F74"143;
"MAA_DQS_H5"
$PN"J73"61;
"MAA_DQS_L9"
$PN"AM72"62;
"MAB1_RSP_L"
$PN"BR74"0;
"MAB_CA5"
$PN"BK72"28;
"MAB_CHECK7"
$PN"BV72"80;
"MAB_DATA1"
$PN"CC73"125;
"MAB_DATA16"
$PN"CP74"106;
"MAB_DATA27"
$PN"DB72"89;
"MAB_DQS_L3"
$PN"DC74"44;
"MAA_CA5"
$PN"BB74"29;
"MAA_DATA1"
$PN"F72"144;
"MAA_DQS_H4"
$PN"AL74"63;
"MAA_DQS_L8"
$PN"AF72"64;
"MAB0_RSP_L"
$PN"BP74"23;
"MAB_CA4"
$PN"BJ73"30;
"MAB_CHECK6"
$PN"BU74"81;
"MAB_DATA0"
$PN"CB74"126;
"MAB_DATA15"
$PN"CP72"107;
"MAB_DATA26"
$PN"DA74"90;
"MAB_DQS_L2"
$PN"CU74"45;
"MAA_CA4"
$PN"BA74"31;
"MAA_DATA0"
$PN"E74"145;
"MAA_DQS_H3"
$PN"AE74"65;
"MAA_DQS_L7"
$PN"Y72"66;
"MAB_CA3"
$PN"BJ74"32;
"MAB_CHECK5"
$PN"BU73"82;
"MAB_DATA14"
$PN"CN74"108;
"MAB_DATA25"
$PN"DA73"91;
"MAB_DQS_L1"
$PN"CL74"46;
"MAA_CA3"
$PN"BA73"33;
"MAA_DATA19"
$PN"W73"127;
"MAA_DQS_H2"
$PN"W74"67;
"MAA_DQS_L6"
$PN"P72"68;
"MAB_CA2"
$PN"BH74"34;
"MAB_CHECK4"
$PN"BT74"83;
"MAB_DATA13"
$PN"CN73"109;
"MAB_DATA24"
$PN"CY74"92;
"MAB_DQS_L0"
$PN"CE74"47;
"MAA_CA2"
$PN"AY72"35;
"MAA_DATA18"
$PN"V74"128;
"MAA_DATA29"
$PN"AH72"129;
"MAA_DQS_H1"
$PN"N74"69;
"MAA_DQS_L5"
$PN"H72"70;
"MAB_CA1"
$PN"BH72"36;
"MAB_CHECK3"
$PN"CB72"84;
"MAB_DATA12"
$PN"CM74"110;
"MAB_DATA23"
$PN"CY72"93;
"MAA_CA1"
$PN"AY74"37;
"MAA_DATA17"
$PN"V72"146;
"MAA_DATA28"
$PN"AG74"130;
"MAA_DQS_H0"
$PN"G74"71;
"MAA_DQS_L4"
$PN"AM74"72;
"MAB_CA0"
$PN"BG73"38;
"MAB_CHECK2"
$PN"CA74"85;
"MAB_DATA11"
$PN"CK72"111;
"MAB_DATA22"
$PN"CW74"112;
"MAA1_RSP_L"
$PN"BP72"0;
"MAA_CA0"
$PN"AW74"39;
"MAA_CHECK7"
$PN"AR73"94;
"MAA_DATA16"
$PN"U74"147;
"MAA_DATA27"
$PN"AE73"131;
"MAA_DQS_L3"
$PN"AF74"73;
"MAB_CHECK1"
$PN"CA73"86;
"MAB_DATA10"
$PN"CJ74"113;
"MAB_DATA21"
$PN"CW73"114;
"MAA0_RSP_L"
$PN"BN73"19;
"MAA_CHECK6"
$PN"AP74"95;
"MAA_DATA15"
$PN"U73"148;
"MAA_DATA26"
$PN"AD74"132;
"MAA_DQS_L2"
$PN"Y74"74;
"MAB_CHECK0"
$PN"BY74"87;
"MAB_DATA20"
$PN"CV74"115;
"MAB_DATA31"
$PN"DF74"96;
"MAA_CHECK5"
$PN"AP72"97;
"MAA_DATA14"
$PN"T74"149;
"MAA_DATA25"
$PN"AD72"133;
"MAA_DQS_L1"
$PN"P74"75;
"MAB1_CS_L1"
$PN"BM74"0;
"MAB_DATA30"
$PN"DE74"98;
"MAB_DQS_H8"
$PN"DD72"48;
"MAA_CHECK4"
$PN"AN74"99;
"MAA_DATA13"
$PN"T72"150;
"MAA_DATA24"
$PN"AC74"134;
"MAA_DQS_L0"
$PN"H74"76;
"MAB0_CS_L1"
$PN"BN74"22;
"MAB1_CS_L0"
$PN"BL73"0;
"MAB_DATA9"
$PN"CJ73"116;
"MAB_DQS_H7"
$PN"CV72"49;
"MAA_CHECK3"
$PN"AL73"100;
"MAA_DATA9"
$PN"M72"151;
"MAA_DATA12"
$PN"R74"152;
"MAA_DATA23"
$PN"AC73"135;
"MAB0_CS_L0"
$PN"BM72"21;
"MAB_DATA8"
$PN"CH74"117;
"MAB_DQS_H6"
$PN"CM72"50;
"MAA_CHECK2"
$PN"AK74"101;
"MAA_DATA8"
$PN"L74"153;
"MAA_DATA11"
$PN"N73"154;
"MAA_DATA22"
$PN"AB74"136;
"MAB_DATA7"
$PN"CH72"118;
"MAB_DQS_H5"
$PN"CF72"51;
"MAB_DQS_L9"
$PN"BW74"40;
"MAA_CHECK1"
$PN"AK72"102;
"MAA_DATA7"
$PN"L73"155;
"MAA_DATA10"
$PN"M74"156;
"MAA_DATA21"
$PN"AB72"137;
"MAB_DATA6"
$PN"CG74"119;
"MAB_DQS_H4"
$PN"BY72"52;
"MAB_DQS_L8"
$PN"DC73"53;
"MAA_CHECK0"
$PN"AJ74"103;
"MAA_DATA6"
$PN"K74"157;
"MAA_DATA20"
$PN"AA74"138;
"MAA_DATA31"
$PN"AJ73"139;
"MAA_DQS_H9"
$PN"AN73"77;
"MAB_DATA5"
$PN"CG73"120;
"MAB_DQS_H3"
$PN"DB74"54;
"MAB_DQS_L7"
$PN"CU73"55;
"MAA1_CS_L1"
$PN"AV72"0;
"MAA_DATA5"
$PN"K72"158;
"MAA_DATA30"
$PN"AH74"140;
"MAA_DQS_H8"
$PN"AG73"78;
"MAB_DATA4"
$PN"CF74"121;
"MAB_DATA19"
$PN"CT72"122;
"MAB_DQS_H2"
$PN"CT74"56;
"MAB_DQS_L6"
$PN"CL73"57;
"MAA0_CS_L1"
$PN"AW73"18;
"MAA1_CS_L0"
$PN"AU74"0;
"MAA_DATA4"
$PN"J74"159;
"MAA_DQS_H7"
$PN"AA73"79;
"MAB_DATA3"
$PN"CD72"141;
"MAB_DATA18"
$PN"CR74"123;
"MAB_DATA29"
$PN"DE73"104;
"MAB_DQS_H1"
$PN"CK74"58;
"MAB_DQS_L5"
$PN"CE73"59;
"MA_RESET_L"
$PN"AT74"25;
"MA_ALERT_L"
$PN"AR74"12;
%"TAP"
"1","(-3300,6025)","0","mstr_standard","I170";
;
CDS_LIB"mstr_standard"
BODY_TYPE"PLUMBING"
HDL_TAP"TRUE";
"B \NAC \NWC"1;
"S \NAC"
BN"1"144;
%"TAP"
"1","(-3300,6075)","0","mstr_standard","I171";
;
CDS_LIB"mstr_standard"
BODY_TYPE"PLUMBING"
HDL_TAP"TRUE";
"B \NAC \NWC"1;
"S \NAC"
BN"0"145;
%"TAP"
"1","(-3300,5975)","0","mstr_standard","I172";
;
CDS_LIB"mstr_standard"
BODY_TYPE"PLUMBING"
HDL_TAP"TRUE";
"B \NAC \NWC"1;
"S \NAC"
BN"2"143;
%"TAP"
"1","(-3300,5925)","0","mstr_standard","I173";
;
CDS_LIB"mstr_standard"
BODY_TYPE"PLUMBING"
HDL_TAP"TRUE";
"B \NAC \NWC"1;
"S \NAC"
BN"3"142;
%"TAP"
"1","(-3300,5825)","0","mstr_standard","I174";
;
CDS_LIB"mstr_standard"
BODY_TYPE"PLUMBING"
HDL_TAP"TRUE";
"B \NAC \NWC"1;
"S \NAC"
BN"5"158;
%"TAP"
"1","(-3300,5875)","0","mstr_standard","I175";
;
CDS_LIB"mstr_standard"
BODY_TYPE"PLUMBING"
HDL_TAP"TRUE";
"B \NAC \NWC"1;
"S \NAC"
BN"4"159;
%"TAP"
"1","(-3300,5775)","0","mstr_standard","I176";
;
CDS_LIB"mstr_standard"
BODY_TYPE"PLUMBING"
HDL_TAP"TRUE";
"B \NAC \NWC"1;
"S \NAC"
BN"6"157;
%"TAP"
"1","(-3300,5725)","0","mstr_standard","I177";
;
CDS_LIB"mstr_standard"
BODY_TYPE"PLUMBING"
HDL_TAP"TRUE";
"B \NAC \NWC"1;
"S \NAC"
BN"7"155;
%"TAP"
"1","(-3300,5575)","0","mstr_standard","I178";
;
CDS_LIB"mstr_standard"
BODY_TYPE"PLUMBING"
HDL_TAP"TRUE";
"B \NAC \NWC"1;
"S \NAC"
BN"9"151;
%"TAP"
"1","(-3300,5625)","0","mstr_standard","I179";
;
CDS_LIB"mstr_standard"
BODY_TYPE"PLUMBING"
HDL_TAP"TRUE";
"B \NAC \NWC"1;
"S \NAC"
BN"8"153;
%"TAP"
"1","(-3300,5525)","0","mstr_standard","I180";
;
CDS_LIB"mstr_standard"
BODY_TYPE"PLUMBING"
HDL_TAP"TRUE";
"B \NAC \NWC"1;
"S \NAC"
BN"10"156;
%"TAP"
"1","(-3300,5425)","0","mstr_standard","I181";
;
CDS_LIB"mstr_standard"
BODY_TYPE"PLUMBING"
HDL_TAP"TRUE";
"B \NAC \NWC"1;
"S \NAC"
BN"12"152;
%"TAP"
"1","(-3300,5475)","0","mstr_standard","I182";
;
CDS_LIB"mstr_standard"
BODY_TYPE"PLUMBING"
HDL_TAP"TRUE";
"B \NAC \NWC"1;
"S \NAC"
BN"11"154;
%"TAP"
"1","(-3300,5325)","0","mstr_standard","I183";
;
CDS_LIB"mstr_standard"
BODY_TYPE"PLUMBING"
HDL_TAP"TRUE";
"B \NAC \NWC"1;
"S \NAC"
BN"14"149;
%"TAP"
"1","(-3300,5375)","0","mstr_standard","I184";
;
CDS_LIB"mstr_standard"
BODY_TYPE"PLUMBING"
HDL_TAP"TRUE";
"B \NAC \NWC"1;
"S \NAC"
BN"13"150;
%"TAP"
"1","(-3300,5275)","0","mstr_standard","I185";
;
CDS_LIB"mstr_standard"
BODY_TYPE"PLUMBING"
HDL_TAP"TRUE";
"B \NAC \NWC"1;
"S \NAC"
BN"15"148;
%"TAP"
"1","(-3300,5125)","0","mstr_standard","I186";
;
CDS_LIB"mstr_standard"
BODY_TYPE"PLUMBING"
HDL_TAP"TRUE";
"B \NAC \NWC"1;
"S \NAC"
BN"17"146;
%"TAP"
"1","(-3300,5175)","0","mstr_standard","I187";
;
CDS_LIB"mstr_standard"
BODY_TYPE"PLUMBING"
HDL_TAP"TRUE";
"B \NAC \NWC"1;
"S \NAC"
BN"16"147;
%"TAP"
"1","(-3300,5075)","0","mstr_standard","I188";
;
CDS_LIB"mstr_standard"
BODY_TYPE"PLUMBING"
HDL_TAP"TRUE";
"B \NAC \NWC"1;
"S \NAC"
BN"18"128;
%"TAP"
"1","(-3300,5025)","0","mstr_standard","I189";
;
CDS_LIB"mstr_standard"
BODY_TYPE"PLUMBING"
HDL_TAP"TRUE";
"B \NAC \NWC"1;
"S \NAC"
BN"19"127;
%"TAP"
"1","(-3300,4975)","0","mstr_standard","I190";
;
CDS_LIB"mstr_standard"
BODY_TYPE"PLUMBING"
HDL_TAP"TRUE";
"B \NAC \NWC"1;
"S \NAC"
BN"20"138;
%"TAP"
"1","(-3300,4875)","0","mstr_standard","I191";
;
CDS_LIB"mstr_standard"
BODY_TYPE"PLUMBING"
HDL_TAP"TRUE";
"B \NAC \NWC"1;
"S \NAC"
BN"22"136;
%"TAP"
"1","(-3300,4925)","0","mstr_standard","I192";
;
CDS_LIB"mstr_standard"
BODY_TYPE"PLUMBING"
HDL_TAP"TRUE";
"B \NAC \NWC"1;
"S \NAC"
BN"21"137;
%"TAP"
"1","(-3300,4825)","0","mstr_standard","I193";
;
CDS_LIB"mstr_standard"
BODY_TYPE"PLUMBING"
HDL_TAP"TRUE";
"B \NAC \NWC"1;
"S \NAC"
BN"23"135;
%"TAP"
"1","(-3300,4675)","0","mstr_standard","I194";
;
CDS_LIB"mstr_standard"
BODY_TYPE"PLUMBING"
HDL_TAP"TRUE";
"B \NAC \NWC"1;
"S \NAC"
BN"25"133;
%"TAP"
"1","(-3300,4725)","0","mstr_standard","I195";
;
CDS_LIB"mstr_standard"
BODY_TYPE"PLUMBING"
HDL_TAP"TRUE";
"B \NAC \NWC"1;
"S \NAC"
BN"24"134;
%"TAP"
"1","(-3300,4625)","0","mstr_standard","I196";
;
CDS_LIB"mstr_standard"
BODY_TYPE"PLUMBING"
HDL_TAP"TRUE";
"B \NAC \NWC"1;
"S \NAC"
BN"26"132;
%"TAP"
"1","(-3300,4575)","0","mstr_standard","I197";
;
CDS_LIB"mstr_standard"
BODY_TYPE"PLUMBING"
HDL_TAP"TRUE";
"B \NAC \NWC"1;
"S \NAC"
BN"27"131;
%"TAP"
"1","(-3300,4525)","0","mstr_standard","I198";
;
CDS_LIB"mstr_standard"
BODY_TYPE"PLUMBING"
HDL_TAP"TRUE";
"B \NAC \NWC"1;
"S \NAC"
BN"28"130;
%"TAP"
"1","(-3300,4475)","0","mstr_standard","I199";
;
CDS_LIB"mstr_standard"
BODY_TYPE"PLUMBING"
HDL_TAP"TRUE";
"B \NAC \NWC"1;
"S \NAC"
BN"29"129;
%"TAP"
"1","(-3300,4425)","0","mstr_standard","I200";
;
CDS_LIB"mstr_standard"
BODY_TYPE"PLUMBING"
HDL_TAP"TRUE";
"B \NAC \NWC"1;
"S \NAC"
BN"30"140;
%"TAP"
"1","(-3300,4375)","0","mstr_standard","I201";
;
CDS_LIB"mstr_standard"
BODY_TYPE"PLUMBING"
HDL_TAP"TRUE";
"B \NAC \NWC"1;
"S \NAC"
BN"31"139;
%"TAP"
"1","(-3300,4225)","0","mstr_standard","I202";
;
CDS_LIB"mstr_standard"
BODY_TYPE"PLUMBING"
HDL_TAP"TRUE";
"B \NAC \NWC"2;
"S \NAC"
BN"1"125;
%"TAP"
"1","(-3300,4275)","0","mstr_standard","I203";
;
CDS_LIB"mstr_standard"
BODY_TYPE"PLUMBING"
HDL_TAP"TRUE";
"B \NAC \NWC"2;
"S \NAC"
BN"0"126;
%"TAP"
"1","(-3300,4125)","0","mstr_standard","I204";
;
CDS_LIB"mstr_standard"
BODY_TYPE"PLUMBING"
HDL_TAP"TRUE";
"B \NAC \NWC"2;
"S \NAC"
BN"3"141;
%"TAP"
"1","(-3300,4175)","0","mstr_standard","I205";
;
CDS_LIB"mstr_standard"
BODY_TYPE"PLUMBING"
HDL_TAP"TRUE";
"B \NAC \NWC"2;
"S \NAC"
BN"2"124;
%"TAP"
"1","(-3300,4075)","0","mstr_standard","I207";
;
CDS_LIB"mstr_standard"
BODY_TYPE"PLUMBING"
HDL_TAP"TRUE";
"B \NAC \NWC"2;
"S \NAC"
BN"4"121;
%"TAP"
"1","(-3300,3975)","0","mstr_standard","I208";
;
CDS_LIB"mstr_standard"
BODY_TYPE"PLUMBING"
HDL_TAP"TRUE";
"B \NAC \NWC"2;
"S \NAC"
BN"6"119;
%"TAP"
"1","(-3300,4025)","0","mstr_standard","I209";
;
CDS_LIB"mstr_standard"
BODY_TYPE"PLUMBING"
HDL_TAP"TRUE";
"B \NAC \NWC"2;
"S \NAC"
BN"5"120;
%"TAP"
"1","(-3300,3925)","0","mstr_standard","I210";
;
CDS_LIB"mstr_standard"
BODY_TYPE"PLUMBING"
HDL_TAP"TRUE";
"B \NAC \NWC"2;
"S \NAC"
BN"7"118;
%"TAP"
"1","(-3300,3825)","0","mstr_standard","I211";
;
CDS_LIB"mstr_standard"
BODY_TYPE"PLUMBING"
HDL_TAP"TRUE";
"B \NAC \NWC"2;
"S \NAC"
BN"8"117;
%"TAP"
"1","(-3300,3725)","0","mstr_standard","I212";
;
CDS_LIB"mstr_standard"
BODY_TYPE"PLUMBING"
HDL_TAP"TRUE";
"B \NAC \NWC"2;
"S \NAC"
BN"10"113;
%"TAP"
"1","(-3300,3775)","0","mstr_standard","I213";
;
CDS_LIB"mstr_standard"
BODY_TYPE"PLUMBING"
HDL_TAP"TRUE";
"B \NAC \NWC"2;
"S \NAC"
BN"9"116;
%"TAP"
"1","(-3300,3675)","0","mstr_standard","I214";
;
CDS_LIB"mstr_standard"
BODY_TYPE"PLUMBING"
HDL_TAP"TRUE";
"B \NAC \NWC"2;
"S \NAC"
BN"11"111;
%"TAP"
"1","(-3300,3625)","0","mstr_standard","I215";
;
CDS_LIB"mstr_standard"
BODY_TYPE"PLUMBING"
HDL_TAP"TRUE";
"B \NAC \NWC"2;
"S \NAC"
BN"12"110;
%"TAP"
"1","(-3300,3525)","0","mstr_standard","I216";
;
CDS_LIB"mstr_standard"
BODY_TYPE"PLUMBING"
HDL_TAP"TRUE";
"B \NAC \NWC"2;
"S \NAC"
BN"14"108;
%"TAP"
"1","(-3300,3575)","0","mstr_standard","I217";
;
CDS_LIB"mstr_standard"
BODY_TYPE"PLUMBING"
HDL_TAP"TRUE";
"B \NAC \NWC"2;
"S \NAC"
BN"13"109;
%"TAP"
"1","(-3300,3475)","0","mstr_standard","I218";
;
CDS_LIB"mstr_standard"
BODY_TYPE"PLUMBING"
HDL_TAP"TRUE";
"B \NAC \NWC"2;
"S \NAC"
BN"15"107;
%"TAP"
"1","(-3300,3375)","0","mstr_standard","I219";
;
CDS_LIB"mstr_standard"
BODY_TYPE"PLUMBING"
HDL_TAP"TRUE";
"B \NAC \NWC"2;
"S \NAC"
BN"16"106;
%"TAP"
"1","(-3300,3275)","0","mstr_standard","I220";
;
CDS_LIB"mstr_standard"
BODY_TYPE"PLUMBING"
HDL_TAP"TRUE";
"B \NAC \NWC"2;
"S \NAC"
BN"18"123;
%"TAP"
"1","(-3300,3325)","0","mstr_standard","I221";
;
CDS_LIB"mstr_standard"
BODY_TYPE"PLUMBING"
HDL_TAP"TRUE";
"B \NAC \NWC"2;
"S \NAC"
BN"17"105;
%"TAP"
"1","(-3300,3225)","0","mstr_standard","I222";
;
CDS_LIB"mstr_standard"
BODY_TYPE"PLUMBING"
HDL_TAP"TRUE";
"B \NAC \NWC"2;
"S \NAC"
BN"19"122;
%"TAP"
"1","(-3300,3175)","0","mstr_standard","I223";
;
CDS_LIB"mstr_standard"
BODY_TYPE"PLUMBING"
HDL_TAP"TRUE";
"B \NAC \NWC"2;
"S \NAC"
BN"20"115;
%"TAP"
"1","(-3300,3125)","0","mstr_standard","I224";
;
CDS_LIB"mstr_standard"
BODY_TYPE"PLUMBING"
HDL_TAP"TRUE";
"B \NAC \NWC"2;
"S \NAC"
BN"21"114;
%"TAP"
"1","(-3300,3075)","0","mstr_standard","I225";
;
CDS_LIB"mstr_standard"
BODY_TYPE"PLUMBING"
HDL_TAP"TRUE";
"B \NAC \NWC"2;
"S \NAC"
BN"22"112;
%"TAP"
"1","(-3300,3025)","0","mstr_standard","I226";
;
CDS_LIB"mstr_standard"
BODY_TYPE"PLUMBING"
HDL_TAP"TRUE";
"B \NAC \NWC"2;
"S \NAC"
BN"23"93;
%"TAP"
"1","(-3300,2925)","0","mstr_standard","I227";
;
CDS_LIB"mstr_standard"
BODY_TYPE"PLUMBING"
HDL_TAP"TRUE";
"B \NAC \NWC"2;
"S \NAC"
BN"24"92;
%"TAP"
"1","(-3300,2875)","0","mstr_standard","I228";
;
CDS_LIB"mstr_standard"
BODY_TYPE"PLUMBING"
HDL_TAP"TRUE";
"B \NAC \NWC"2;
"S \NAC"
BN"25"91;
%"TAP"
"1","(-3300,2825)","0","mstr_standard","I229";
;
CDS_LIB"mstr_standard"
BODY_TYPE"PLUMBING"
HDL_TAP"TRUE";
"B \NAC \NWC"2;
"S \NAC"
BN"26"90;
%"TAP"
"1","(-3300,2775)","0","mstr_standard","I230";
;
CDS_LIB"mstr_standard"
BODY_TYPE"PLUMBING"
HDL_TAP"TRUE";
"B \NAC \NWC"2;
"S \NAC"
BN"27"89;
%"TAP"
"1","(-3300,2725)","0","mstr_standard","I231";
;
CDS_LIB"mstr_standard"
BODY_TYPE"PLUMBING"
HDL_TAP"TRUE";
"B \NAC \NWC"2;
"S \NAC"
BN"28"88;
%"TAP"
"1","(-3300,2675)","0","mstr_standard","I232";
;
CDS_LIB"mstr_standard"
BODY_TYPE"PLUMBING"
HDL_TAP"TRUE";
"B \NAC \NWC"2;
"S \NAC"
BN"29"104;
%"TAP"
"1","(-3300,2625)","0","mstr_standard","I233";
;
CDS_LIB"mstr_standard"
BODY_TYPE"PLUMBING"
HDL_TAP"TRUE";
"B \NAC \NWC"2;
"S \NAC"
BN"30"98;
%"TAP"
"1","(-3300,2575)","0","mstr_standard","I234";
;
CDS_LIB"mstr_standard"
BODY_TYPE"PLUMBING"
HDL_TAP"TRUE";
"B \NAC \NWC"2;
"S \NAC"
BN"31"96;
%"TAP"
"1","(-3300,2475)","0","mstr_standard","I235";
;
CDS_LIB"mstr_standard"
BODY_TYPE"PLUMBING"
HDL_TAP"TRUE";
"B \NAC \NWC"3;
"S \NAC"
BN"0"103;
%"TAP"
"1","(-3300,2375)","0","mstr_standard","I236";
;
CDS_LIB"mstr_standard"
BODY_TYPE"PLUMBING"
HDL_TAP"TRUE";
"B \NAC \NWC"3;
"S \NAC"
BN"2"101;
%"TAP"
"1","(-3300,2425)","0","mstr_standard","I237";
;
CDS_LIB"mstr_standard"
BODY_TYPE"PLUMBING"
HDL_TAP"TRUE";
"B \NAC \NWC"3;
"S \NAC"
BN"1"102;
%"TAP"
"1","(-3300,2325)","0","mstr_standard","I238";
;
CDS_LIB"mstr_standard"
BODY_TYPE"PLUMBING"
HDL_TAP"TRUE";
"B \NAC \NWC"3;
"S \NAC"
BN"3"100;
%"TAP"
"1","(-3300,2275)","0","mstr_standard","I239";
;
CDS_LIB"mstr_standard"
BODY_TYPE"PLUMBING"
HDL_TAP"TRUE";
"B \NAC \NWC"3;
"S \NAC"
BN"4"99;
%"TAP"
"1","(-3300,2225)","0","mstr_standard","I240";
;
CDS_LIB"mstr_standard"
BODY_TYPE"PLUMBING"
HDL_TAP"TRUE";
"B \NAC \NWC"3;
"S \NAC"
BN"5"97;
%"TAP"
"1","(-3300,2175)","0","mstr_standard","I241";
;
CDS_LIB"mstr_standard"
BODY_TYPE"PLUMBING"
HDL_TAP"TRUE";
"B \NAC \NWC"3;
"S \NAC"
BN"6"95;
%"TAP"
"1","(-3300,2125)","0","mstr_standard","I242";
;
CDS_LIB"mstr_standard"
BODY_TYPE"PLUMBING"
HDL_TAP"TRUE";
"B \NAC \NWC"3;
"S \NAC"
BN"7"94;
%"TAP"
"1","(-3300,2025)","0","mstr_standard","I244";
;
CDS_LIB"mstr_standard"
BODY_TYPE"PLUMBING"
HDL_TAP"TRUE";
"B \NAC \NWC"4;
"S \NAC"
BN"0"87;
%"TAP"
"1","(-3300,1975)","0","mstr_standard","I245";
;
CDS_LIB"mstr_standard"
BODY_TYPE"PLUMBING"
HDL_TAP"TRUE";
"B \NAC \NWC"4;
"S \NAC"
BN"1"86;
%"TAP"
"1","(-3300,1925)","0","mstr_standard","I246";
;
CDS_LIB"mstr_standard"
BODY_TYPE"PLUMBING"
HDL_TAP"TRUE";
"B \NAC \NWC"4;
"S \NAC"
BN"2"85;
%"TAP"
"1","(-3300,1825)","0","mstr_standard","I247";
;
CDS_LIB"mstr_standard"
BODY_TYPE"PLUMBING"
HDL_TAP"TRUE";
"B \NAC \NWC"4;
"S \NAC"
BN"4"83;
%"TAP"
"1","(-3300,1875)","0","mstr_standard","I248";
;
CDS_LIB"mstr_standard"
BODY_TYPE"PLUMBING"
HDL_TAP"TRUE";
"B \NAC \NWC"4;
"S \NAC"
BN"3"84;
%"TAP"
"1","(-3300,1775)","0","mstr_standard","I249";
;
CDS_LIB"mstr_standard"
BODY_TYPE"PLUMBING"
HDL_TAP"TRUE";
"B \NAC \NWC"4;
"S \NAC"
BN"5"82;
%"TAP"
"1","(-3300,1675)","0","mstr_standard","I250";
;
CDS_LIB"mstr_standard"
BODY_TYPE"PLUMBING"
HDL_TAP"TRUE";
"B \NAC \NWC"4;
"S \NAC"
BN"7"80;
%"TAP"
"1","(-3300,1725)","0","mstr_standard","I251";
;
CDS_LIB"mstr_standard"
BODY_TYPE"PLUMBING"
HDL_TAP"TRUE";
"B \NAC \NWC"4;
"S \NAC"
BN"6"81;
%"TAP"
"1","(-5725,6075)","2","mstr_standard","I252";
;
CDS_LIB"mstr_standard"
BODY_TYPE"PLUMBING"
HDL_TAP"TRUE";
"B \NAC \NWC"5;
"S \NAC"
BN"0"71;
%"TAP"
"1","(-5725,5975)","2","mstr_standard","I253";
;
CDS_LIB"mstr_standard"
BODY_TYPE"PLUMBING"
HDL_TAP"TRUE";
"B \NAC \NWC"5;
"S \NAC"
BN"1"69;
%"TAP"
"1","(-5725,5875)","2","mstr_standard","I254";
;
CDS_LIB"mstr_standard"
BODY_TYPE"PLUMBING"
HDL_TAP"TRUE";
"B \NAC \NWC"5;
"S \NAC"
BN"2"67;
%"TAP"
"1","(-5925,6025)","2","mstr_standard","I255";
;
CDS_LIB"mstr_standard"
BODY_TYPE"PLUMBING"
HDL_TAP"TRUE";
"B \NAC \NWC"6;
"S \NAC"
BN"0"76;
%"TAP"
"1","(-5925,5925)","2","mstr_standard","I256";
;
CDS_LIB"mstr_standard"
BODY_TYPE"PLUMBING"
HDL_TAP"TRUE";
"B \NAC \NWC"6;
"S \NAC"
BN"1"75;
%"TAP"
"1","(-5725,5775)","2","mstr_standard","I257";
;
CDS_LIB"mstr_standard"
BODY_TYPE"PLUMBING"
HDL_TAP"TRUE";
"B \NAC \NWC"5;
"S \NAC"
BN"3"65;
%"TAP"
"1","(-5725,5675)","2","mstr_standard","I258";
;
CDS_LIB"mstr_standard"
BODY_TYPE"PLUMBING"
HDL_TAP"TRUE";
"B \NAC \NWC"5;
"S \NAC"
BN"4"63;
%"TAP"
"1","(-5925,5825)","2","mstr_standard","I259";
;
CDS_LIB"mstr_standard"
BODY_TYPE"PLUMBING"
HDL_TAP"TRUE";
"B \NAC \NWC"6;
"S \NAC"
BN"2"74;
%"TAP"
"1","(-5925,5725)","2","mstr_standard","I260";
;
CDS_LIB"mstr_standard"
BODY_TYPE"PLUMBING"
HDL_TAP"TRUE";
"B \NAC \NWC"6;
"S \NAC"
BN"3"73;
%"TAP"
"1","(-5725,5575)","2","mstr_standard","I261";
;
CDS_LIB"mstr_standard"
BODY_TYPE"PLUMBING"
HDL_TAP"TRUE";
"B \NAC \NWC"5;
"S \NAC"
BN"5"61;
%"TAP"
"1","(-5725,5375)","2","mstr_standard","I262";
;
CDS_LIB"mstr_standard"
BODY_TYPE"PLUMBING"
HDL_TAP"TRUE";
"B \NAC \NWC"5;
"S \NAC"
BN"7"79;
%"TAP"
"1","(-5725,5475)","2","mstr_standard","I263";
;
CDS_LIB"mstr_standard"
BODY_TYPE"PLUMBING"
HDL_TAP"TRUE";
"B \NAC \NWC"5;
"S \NAC"
BN"6"60;
%"TAP"
"1","(-5925,5625)","2","mstr_standard","I264";
;
CDS_LIB"mstr_standard"
BODY_TYPE"PLUMBING"
HDL_TAP"TRUE";
"B \NAC \NWC"6;
"S \NAC"
BN"4"72;
%"TAP"
"1","(-5925,5525)","2","mstr_standard","I265";
;
CDS_LIB"mstr_standard"
BODY_TYPE"PLUMBING"
HDL_TAP"TRUE";
"B \NAC \NWC"6;
"S \NAC"
BN"5"70;
%"TAP"
"1","(-5925,5425)","2","mstr_standard","I266";
;
CDS_LIB"mstr_standard"
BODY_TYPE"PLUMBING"
HDL_TAP"TRUE";
"B \NAC \NWC"6;
"S \NAC"
BN"6"68;
%"TAP"
"1","(-5725,5275)","2","mstr_standard","I267";
;
CDS_LIB"mstr_standard"
BODY_TYPE"PLUMBING"
HDL_TAP"TRUE";
"B \NAC \NWC"5;
"S \NAC"
BN"8"78;
%"TAP"
"1","(-5725,5175)","2","mstr_standard","I268";
;
CDS_LIB"mstr_standard"
BODY_TYPE"PLUMBING"
HDL_TAP"TRUE";
"B \NAC \NWC"5;
"S \NAC"
BN"9"77;
%"TAP"
"1","(-5925,5325)","2","mstr_standard","I269";
;
CDS_LIB"mstr_standard"
BODY_TYPE"PLUMBING"
HDL_TAP"TRUE";
"B \NAC \NWC"6;
"S \NAC"
BN"7"66;
%"TAP"
"1","(-5925,5225)","2","mstr_standard","I270";
;
CDS_LIB"mstr_standard"
BODY_TYPE"PLUMBING"
HDL_TAP"TRUE";
"B \NAC \NWC"6;
"S \NAC"
BN"8"64;
%"TAP"
"1","(-5925,5125)","2","mstr_standard","I271";
;
CDS_LIB"mstr_standard"
BODY_TYPE"PLUMBING"
HDL_TAP"TRUE";
"B \NAC \NWC"6;
"S \NAC"
BN"9"62;
%"TAP"
"1","(-5725,5025)","2","mstr_standard","I272";
;
CDS_LIB"mstr_standard"
BODY_TYPE"PLUMBING"
HDL_TAP"TRUE";
"B \NAC \NWC"8;
"S \NAC"
BN"0"42;
%"TAP"
"1","(-5725,4925)","2","mstr_standard","I273";
;
CDS_LIB"mstr_standard"
BODY_TYPE"PLUMBING"
HDL_TAP"TRUE";
"B \NAC \NWC"8;
"S \NAC"
BN"1"58;
%"TAP"
"1","(-5925,4975)","2","mstr_standard","I274";
;
CDS_LIB"mstr_standard"
BODY_TYPE"PLUMBING"
HDL_TAP"TRUE";
"B \NAC \NWC"7;
"S \NAC"
BN"0"47;
%"TAP"
"1","(-5925,4875)","2","mstr_standard","I275";
;
CDS_LIB"mstr_standard"
BODY_TYPE"PLUMBING"
HDL_TAP"TRUE";
"B \NAC \NWC"7;
"S \NAC"
BN"1"46;
%"TAP"
"1","(-5725,4825)","2","mstr_standard","I276";
;
CDS_LIB"mstr_standard"
BODY_TYPE"PLUMBING"
HDL_TAP"TRUE";
"B \NAC \NWC"8;
"S \NAC"
BN"2"56;
%"TAP"
"1","(-5725,4725)","2","mstr_standard","I277";
;
CDS_LIB"mstr_standard"
BODY_TYPE"PLUMBING"
HDL_TAP"TRUE";
"B \NAC \NWC"8;
"S \NAC"
BN"3"54;
%"TAP"
"1","(-5725,4625)","2","mstr_standard","I278";
;
CDS_LIB"mstr_standard"
BODY_TYPE"PLUMBING"
HDL_TAP"TRUE";
"B \NAC \NWC"8;
"S \NAC"
BN"4"52;
%"TAP"
"1","(-5925,4775)","2","mstr_standard","I279";
;
CDS_LIB"mstr_standard"
BODY_TYPE"PLUMBING"
HDL_TAP"TRUE";
"B \NAC \NWC"7;
"S \NAC"
BN"2"45;
%"TAP"
"1","(-5925,4675)","2","mstr_standard","I280";
;
CDS_LIB"mstr_standard"
BODY_TYPE"PLUMBING"
HDL_TAP"TRUE";
"B \NAC \NWC"7;
"S \NAC"
BN"3"44;
%"TAP"
"1","(-5725,4525)","2","mstr_standard","I281";
;
CDS_LIB"mstr_standard"
BODY_TYPE"PLUMBING"
HDL_TAP"TRUE";
"B \NAC \NWC"8;
"S \NAC"
BN"5"51;
%"TAP"
"1","(-5725,4425)","2","mstr_standard","I282";
;
CDS_LIB"mstr_standard"
BODY_TYPE"PLUMBING"
HDL_TAP"TRUE";
"B \NAC \NWC"8;
"S \NAC"
BN"6"50;
%"TAP"
"1","(-5925,4575)","2","mstr_standard","I283";
;
CDS_LIB"mstr_standard"
BODY_TYPE"PLUMBING"
HDL_TAP"TRUE";
"B \NAC \NWC"7;
"S \NAC"
BN"4"43;
%"TAP"
"1","(-5925,4475)","2","mstr_standard","I284";
;
CDS_LIB"mstr_standard"
BODY_TYPE"PLUMBING"
HDL_TAP"TRUE";
"B \NAC \NWC"7;
"S \NAC"
BN"5"59;
%"TAP"
"1","(-5925,4375)","2","mstr_standard","I285";
;
CDS_LIB"mstr_standard"
BODY_TYPE"PLUMBING"
HDL_TAP"TRUE";
"B \NAC \NWC"7;
"S \NAC"
BN"6"57;
%"TAP"
"1","(-5725,4325)","2","mstr_standard","I286";
;
CDS_LIB"mstr_standard"
BODY_TYPE"PLUMBING"
HDL_TAP"TRUE";
"B \NAC \NWC"8;
"S \NAC"
BN"7"49;
%"TAP"
"1","(-5725,4225)","2","mstr_standard","I287";
;
CDS_LIB"mstr_standard"
BODY_TYPE"PLUMBING"
HDL_TAP"TRUE";
"B \NAC \NWC"8;
"S \NAC"
BN"8"48;
%"TAP"
"1","(-5725,4125)","2","mstr_standard","I288";
;
CDS_LIB"mstr_standard"
BODY_TYPE"PLUMBING"
HDL_TAP"TRUE";
"B \NAC \NWC"8;
"S \NAC"
BN"9"41;
%"TAP"
"1","(-5925,4275)","2","mstr_standard","I289";
;
CDS_LIB"mstr_standard"
BODY_TYPE"PLUMBING"
HDL_TAP"TRUE";
"B \NAC \NWC"7;
"S \NAC"
BN"7"55;
%"TAP"
"1","(-5925,4175)","2","mstr_standard","I290";
;
CDS_LIB"mstr_standard"
BODY_TYPE"PLUMBING"
HDL_TAP"TRUE";
"B \NAC \NWC"7;
"S \NAC"
BN"8"53;
%"TAP"
"1","(-5925,4075)","2","mstr_standard","I295";
;
CDS_LIB"mstr_standard"
BODY_TYPE"PLUMBING"
HDL_TAP"TRUE";
"B \NAC \NWC"7;
"S \NAC"
BN"9"40;
%"TAP"
"1","(-5925,3925)","2","mstr_standard","I296";
;
CDS_LIB"mstr_standard"
BODY_TYPE"PLUMBING"
HDL_TAP"TRUE";
"B \NAC \NWC"9;
"S \NAC"
BN"0"39;
%"TAP"
"1","(-5925,3875)","2","mstr_standard","I297";
;
CDS_LIB"mstr_standard"
BODY_TYPE"PLUMBING"
HDL_TAP"TRUE";
"B \NAC \NWC"9;
"S \NAC"
BN"1"37;
%"TAP"
"1","(-5925,3825)","2","mstr_standard","I298";
;
CDS_LIB"mstr_standard"
BODY_TYPE"PLUMBING"
HDL_TAP"TRUE";
"B \NAC \NWC"9;
"S \NAC"
BN"2"35;
%"TAP"
"1","(-5925,3775)","2","mstr_standard","I299";
;
CDS_LIB"mstr_standard"
BODY_TYPE"PLUMBING"
HDL_TAP"TRUE";
"B \NAC \NWC"9;
"S \NAC"
BN"3"33;
%"TAP"
"1","(-5925,3725)","2","mstr_standard","I300";
;
CDS_LIB"mstr_standard"
BODY_TYPE"PLUMBING"
HDL_TAP"TRUE";
"B \NAC \NWC"9;
"S \NAC"
BN"4"31;
%"TAP"
"1","(-5925,3675)","2","mstr_standard","I301";
;
CDS_LIB"mstr_standard"
BODY_TYPE"PLUMBING"
HDL_TAP"TRUE";
"B \NAC \NWC"9;
"S \NAC"
BN"5"29;
%"TAP"
"1","(-5925,3625)","2","mstr_standard","I302";
;
CDS_LIB"mstr_standard"
BODY_TYPE"PLUMBING"
HDL_TAP"TRUE";
"B \NAC \NWC"9;
"S \NAC"
BN"6"27;
%"TAP"
"1","(-5925,3475)","2","mstr_standard","I303";
;
CDS_LIB"mstr_standard"
BODY_TYPE"PLUMBING"
HDL_TAP"TRUE";
"B \NAC \NWC"10;
"S \NAC"
BN"1"36;
%"TAP"
"1","(-5925,3525)","2","mstr_standard","I304";
;
CDS_LIB"mstr_standard"
BODY_TYPE"PLUMBING"
HDL_TAP"TRUE";
"B \NAC \NWC"10;
"S \NAC"
BN"0"38;
%"TAP"
"1","(-5925,3425)","2","mstr_standard","I305";
;
CDS_LIB"mstr_standard"
BODY_TYPE"PLUMBING"
HDL_TAP"TRUE";
"B \NAC \NWC"10;
"S \NAC"
BN"2"34;
%"TAP"
"1","(-5925,3375)","2","mstr_standard","I306";
;
CDS_LIB"mstr_standard"
BODY_TYPE"PLUMBING"
HDL_TAP"TRUE";
"B \NAC \NWC"10;
"S \NAC"
BN"3"32;
%"TAP"
"1","(-5925,3325)","2","mstr_standard","I307";
;
CDS_LIB"mstr_standard"
BODY_TYPE"PLUMBING"
HDL_TAP"TRUE";
"B \NAC \NWC"10;
"S \NAC"
BN"4"30;
%"TAP"
"1","(-5925,3225)","2","mstr_standard","I308";
;
CDS_LIB"mstr_standard"
BODY_TYPE"PLUMBING"
HDL_TAP"TRUE";
"B \NAC \NWC"10;
"S \NAC"
BN"6"26;
%"TAP"
"1","(-5925,3275)","2","mstr_standard","I309";
;
CDS_LIB"mstr_standard"
BODY_TYPE"PLUMBING"
HDL_TAP"TRUE";
"B \NAC \NWC"10;
"S \NAC"
BN"5"28;
%"Q_RES"
"1","(-6600,2225)","0","pure_quanta","I322";
;
LOCATION"R500"
$SEC"1"
CDS_SEC"1"
PACK_TYPE"0402LF"
TOLERANCE"1%"
VALUE"15"
MATERIAL"CHIP"
WATTAGE"1/16W"
CDS_LIB"pure_quanta"
PART_NUMBER"CS01502FB03";
"B"
$PN"2"12;
"A"
$PN"1"11;
END.
